(kicad_pcb
	(version 20260206)
	(generator "pcbnew")
	(generator_version "10.0")
	(general
		(thickness 1.6)
		(legacy_teardrops no)
	)
	(paper "A4")
	(title_block
		(title "01162023_DA0F0TEBIF0_F0T_Expander_BD_F_brd_V02_OCP.brd")
		(comment 1 "Grand Teton / footprints 7507-7515 of 9728")
	)
	(layers
		(0 "F.Cu" signal "TOP")
		(4 "In1.Cu" signal "GND")
		(6 "In2.Cu" signal "VCC")
		(8 "In3.Cu" signal "VCC1")
		(10 "In4.Cu" signal "GND1")
		(12 "In5.Cu" signal "IN1")
		(14 "In6.Cu" signal "GND2")
		(16 "In7.Cu" signal "IN2")
		(18 "In8.Cu" signal "GND3")
		(20 "In9.Cu" signal "IN3")
		(22 "In10.Cu" signal "GND4")
		(24 "In11.Cu" signal "IN4")
		(26 "In12.Cu" signal "GND5")
		(28 "In13.Cu" signal "IN5")
		(30 "In14.Cu" signal "GND6")
		(32 "In15.Cu" signal "IN6")
		(34 "In16.Cu" signal "GND7")
		(2 "B.Cu" signal "BOTTOM")
		(9 "F.Adhes" user "F.Adhesive")
		(11 "B.Adhes" user "B.Adhesive")
		(13 "F.Paste" user "Package Geometry/Pastemask Top")
		(15 "B.Paste" user "Package Geometry/Pastemask Bottom")
		(5 "F.SilkS" user "Ref Des/Silkscreen Top")
		(7 "B.SilkS" user "Ref Des/Silkscreen Bottom")
		(1 "F.Mask" user "Board Geometry/Soldermask Top")
		(3 "B.Mask" user "Board Geometry/Soldermask Bottom")
		(17 "Dwgs.User" user "User.Drawings")
		(19 "Cmts.User" user "User.Comments")
		(21 "Eco1.User" user "User.Eco1")
		(23 "Eco2.User" user "User.Eco2")
		(25 "Edge.Cuts" user "Board Geometry/Outline")
		(27 "Margin" user)
		(31 "F.CrtYd" user "Package Geometry/Place Bound Top")
		(29 "B.CrtYd" user "Package Geometry/Place Bound Bottom")
		(35 "F.Fab" user "Ref Des/Assembly Top")
		(33 "B.Fab" user "Ref Des/Assembly Bottom")
	)
	(footprint ""
		(layer "B.Cu")
		(at 72.949816 -296.8498 180)
		(property "Reference" "C2948"
			(at 0 0 0)
			(layer "B.SilkS")
			(hide yes)
			(effects
				(font
					(size 1.27 1.27)
				)
				(justify mirror)
			)
		)
		(property "Value" ""
			(at 0 0 0)
			(layer "B.Fab")
			(effects
				(font
					(size 1.27 1.27)
				)
				(justify mirror)
			)
		)
		(duplicate_pad_numbers_are_jumpers no)
		(fp_line
			(start 0.299974 0.150114)
			(end 0.299974 -0.150114)
			(stroke
				(width 0.1)
				(type default)
			)
			(layer "B.Fab")
		)
		(fp_line
			(start 0.299974 -0.150114)
			(end -0.299974 -0.150114)
			(stroke
				(width 0.1)
				(type default)
			)
			(layer "B.Fab")
		)
		(fp_line
			(start -0.299974 0.150114)
			(end 0.299974 0.150114)
			(stroke
				(width 0.1)
				(type default)
			)
			(layer "B.Fab")
		)
		(fp_line
			(start -0.299974 -0.150114)
			(end -0.299974 0.150114)
			(stroke
				(width 0.1)
				(type default)
			)
			(layer "B.Fab")
		)
		(pad "1" smd rect
			(at 0.2667 0)
			(size 0.3048 0.381)
			(layers "B.Cu" "B.Mask" "B.Paste")
			(net "P1V25_SERDES_VDDPLL_PEX0")
		)
		(pad "2" smd rect
			(at -0.2667 0)
			(size 0.3048 0.381)
			(layers "B.Cu" "B.Mask" "B.Paste")
			(net "GND")
		)
	)
	(footprint ""
		(layer "B.Cu")
		(at 294.22471 -286.399732 90)
		(property "Reference" "C3306"
			(at 0 0 90)
			(layer "B.SilkS")
			(hide yes)
			(effects
				(font
					(size 1.27 1.27)
				)
				(justify mirror)
			)
		)
		(property "Value" ""
			(at 0 0 90)
			(layer "B.Fab")
			(effects
				(font
					(size 1.27 1.27)
				)
				(justify mirror)
			)
		)
		(duplicate_pad_numbers_are_jumpers no)
		(fp_line
			(start 0.299974 -0.150114)
			(end -0.299974 -0.150114)
			(stroke
				(width 0.1)
				(type default)
			)
			(layer "B.Fab")
		)
		(fp_line
			(start -0.299974 -0.150114)
			(end -0.299974 0.150114)
			(stroke
				(width 0.1)
				(type default)
			)
			(layer "B.Fab")
		)
		(fp_line
			(start 0.299974 0.150114)
			(end 0.299974 -0.150114)
			(stroke
				(width 0.1)
				(type default)
			)
			(layer "B.Fab")
		)
		(fp_line
			(start -0.299974 0.150114)
			(end 0.299974 0.150114)
			(stroke
				(width 0.1)
				(type default)
			)
			(layer "B.Fab")
		)
		(pad "1" smd rect
			(at 0.2667 0 270)
			(size 0.3048 0.381)
			(layers "B.Cu" "B.Mask" "B.Paste")
			(net "P1V25_SERDES_VDDPLL_PEX2")
		)
		(pad "2" smd rect
			(at -0.2667 0 270)
			(size 0.3048 0.381)
			(layers "B.Cu" "B.Mask" "B.Paste")
			(net "GND")
		)
	)
	(footprint ""
		(layer "B.Cu")
		(at 236.927136 -266.873228)
		(property "Reference" "R6134"
			(at 0 0 0)
			(layer "B.SilkS")
			(hide yes)
			(effects
				(font
					(size 1.27 1.27)
				)
				(justify mirror)
			)
		)
		(property "Value" ""
			(at 0 0 0)
			(layer "B.Fab")
			(effects
				(font
					(size 1.27 1.27)
				)
				(justify mirror)
			)
		)
		(duplicate_pad_numbers_are_jumpers no)
		(fp_line
			(start -2.576322 -1.1303)
			(end -2.576322 1.1303)
			(stroke
				(width 0.1524)
				(type default)
			)
			(layer "B.SilkS")
		)
		(fp_line
			(start -2.576322 1.1303)
			(end 2.576322 1.1303)
			(stroke
				(width 0.1524)
				(type default)
			)
			(layer "B.SilkS")
		)
		(fp_line
			(start 2.576322 -1.1303)
			(end -2.576322 -1.1303)
			(stroke
				(width 0.1524)
				(type default)
			)
			(layer "B.SilkS")
		)
		(fp_line
			(start 2.576322 1.1303)
			(end 2.576322 -1.1303)
			(stroke
				(width 0.1524)
				(type default)
			)
			(layer "B.SilkS")
		)
		(fp_line
			(start -1.649984 -0.899922)
			(end 1.649984 -0.899922)
			(stroke
				(width 0.1)
				(type default)
			)
			(layer "B.Fab")
		)
		(fp_line
			(start -1.649984 0.899922)
			(end -1.649984 -0.899922)
			(stroke
				(width 0.1)
				(type default)
			)
			(layer "B.Fab")
		)
		(fp_line
			(start 1.649984 -0.899922)
			(end 1.649984 0.899922)
			(stroke
				(width 0.1)
				(type default)
			)
			(layer "B.Fab")
		)
		(fp_line
			(start 1.649984 0.899922)
			(end -1.649984 0.899922)
			(stroke
				(width 0.1)
				(type default)
			)
			(layer "B.Fab")
		)
		(pad "1A" smd rect
			(at 1.700022 0 180)
			(size 1.4986 2.0066)
			(layers "B.Cu" "B.Mask" "B.Paste")
			(net "P1V25_PEX2")
		)
		(pad "1B" smd rect
			(at 1.077722 0 180)
			(size 0.254 0.508)
			(layers "B.Cu" "B.Mask" "B.Paste")
			(net "P1V25_PEX2")
		)
		(pad "2A" smd rect
			(at -1.700022 0 180)
			(size 1.4986 2.0066)
			(layers "B.Cu" "B.Mask" "B.Paste")
			(net "P1V25_SERDES_VDDPLL_PEX2")
		)
		(pad "2B" smd rect
			(at -1.077722 0 180)
			(size 0.254 0.508)
			(layers "B.Cu" "B.Mask" "B.Paste")
			(net "P1V25_SERDES_VDDPLL_PEX2")
		)
	)
	(footprint ""
		(layer "B.Cu")
		(at 237.521496 -212.332824 -90)
		(property "Reference" "R475"
			(at 0 0 90)
			(layer "B.SilkS")
			(hide yes)
			(effects
				(font
					(size 1.27 1.27)
				)
				(justify mirror)
			)
		)
		(property "Value" ""
			(at 0 0 90)
			(layer "B.Fab")
			(effects
				(font
					(size 1.27 1.27)
				)
				(justify mirror)
			)
		)
		(duplicate_pad_numbers_are_jumpers no)
		(fp_line
			(start -0.7874 0.4064)
			(end 0.7874 0.4064)
			(stroke
				(width 0.1524)
				(type default)
			)
			(layer "B.SilkS")
		)
		(fp_line
			(start 0.7874 0.4064)
			(end 0.7874 -0.4064)
			(stroke
				(width 0.1524)
				(type default)
			)
			(layer "B.SilkS")
		)
		(fp_line
			(start -0.7874 -0.4064)
			(end -0.7874 0.4064)
			(stroke
				(width 0.1524)
				(type default)
			)
			(layer "B.SilkS")
		)
		(fp_line
			(start 0.7874 -0.4064)
			(end -0.7874 -0.4064)
			(stroke
				(width 0.1524)
				(type default)
			)
			(layer "B.SilkS")
		)
		(fp_line
			(start -0.67945 0.3048)
			(end -0.120396 0.3048)
			(stroke
				(width 0.1)
				(type default)
			)
			(layer "B.Fab")
		)
		(fp_line
			(start -0.120396 0.3048)
			(end -0.120396 0.2794)
			(stroke
				(width 0.1)
				(type default)
			)
			(layer "B.Fab")
		)
		(fp_line
			(start 0.12065 0.3048)
			(end 0.67945 0.3048)
			(stroke
				(width 0.1)
				(type default)
			)
			(layer "B.Fab")
		)
		(fp_line
			(start 0.67945 0.3048)
			(end 0.67945 -0.305054)
			(stroke
				(width 0.1)
				(type default)
			)
			(layer "B.Fab")
		)
		(fp_line
			(start -0.120396 0.2794)
			(end 0.12065 0.2794)
			(stroke
				(width 0.1)
				(type default)
			)
			(layer "B.Fab")
		)
		(fp_line
			(start 0.12065 0.2794)
			(end 0.12065 0.3048)
			(stroke
				(width 0.1)
				(type default)
			)
			(layer "B.Fab")
		)
		(fp_line
			(start -0.12065 -0.2794)
			(end -0.12065 -0.3048)
			(stroke
				(width 0.1)
				(type default)
			)
			(layer "B.Fab")
		)
		(fp_line
			(start 0.12065 -0.2794)
			(end -0.12065 -0.2794)
			(stroke
				(width 0.1)
				(type default)
			)
			(layer "B.Fab")
		)
		(fp_line
			(start -0.67945 -0.3048)
			(end -0.67945 0.3048)
			(stroke
				(width 0.1)
				(type default)
			)
			(layer "B.Fab")
		)
		(fp_line
			(start -0.12065 -0.3048)
			(end -0.67945 -0.3048)
			(stroke
				(width 0.1)
				(type default)
			)
			(layer "B.Fab")
		)
		(fp_line
			(start 0.12065 -0.305054)
			(end 0.12065 -0.2794)
			(stroke
				(width 0.1)
				(type default)
			)
			(layer "B.Fab")
		)
		(fp_line
			(start 0.67945 -0.305054)
			(end 0.12065 -0.305054)
			(stroke
				(width 0.1)
				(type default)
			)
			(layer "B.Fab")
		)
		(pad "1" smd circle
			(at 0.40005 0 90)
			(size 0 0)
			(layers "B.Cu" "B.Mask" "B.Paste")
			(net "P1V2_AUX")
		)
		(pad "2" smd circle
			(at -0.40005 0 90)
			(size 0 0)
			(layers "B.Cu" "B.Mask" "B.Paste")
			(net "P1V2_AUX_SCALED")
		)
	)
	(footprint ""
		(layer "B.Cu")
		(at 172.900086 -288.299906 90)
		(property "Reference" "C3116"
			(at 0 0 90)
			(layer "B.SilkS")
			(hide yes)
			(effects
				(font
					(size 1.27 1.27)
				)
				(justify mirror)
			)
		)
		(property "Value" ""
			(at 0 0 90)
			(layer "B.Fab")
			(effects
				(font
					(size 1.27 1.27)
				)
				(justify mirror)
			)
		)
		(duplicate_pad_numbers_are_jumpers no)
		(fp_line
			(start 0.299974 -0.150114)
			(end -0.299974 -0.150114)
			(stroke
				(width 0.1)
				(type default)
			)
			(layer "B.Fab")
		)
		(fp_line
			(start -0.299974 -0.150114)
			(end -0.299974 0.150114)
			(stroke
				(width 0.1)
				(type default)
			)
			(layer "B.Fab")
		)
		(fp_line
			(start 0.299974 0.150114)
			(end 0.299974 -0.150114)
			(stroke
				(width 0.1)
				(type default)
			)
			(layer "B.Fab")
		)
		(fp_line
			(start -0.299974 0.150114)
			(end 0.299974 0.150114)
			(stroke
				(width 0.1)
				(type default)
			)
			(layer "B.Fab")
		)
		(pad "1" smd rect
			(at 0.2667 0 270)
			(size 0.3048 0.381)
			(layers "B.Cu" "B.Mask" "B.Paste")
			(net "P1V25_PEX1")
		)
		(pad "2" smd rect
			(at -0.2667 0 270)
			(size 0.3048 0.381)
			(layers "B.Cu" "B.Mask" "B.Paste")
			(net "GND")
		)
	)
	(footprint ""
		(layer "B.Cu")
		(at 17.869662 -222.658432)
		(property "Reference" "C2216"
			(at 0 0 0)
			(layer "B.SilkS")
			(hide yes)
			(effects
				(font
					(size 1.27 1.27)
				)
				(justify mirror)
			)
		)
		(property "Value" ""
			(at 0 0 0)
			(layer "B.Fab")
			(effects
				(font
					(size 1.27 1.27)
				)
				(justify mirror)
			)
		)
		(duplicate_pad_numbers_are_jumpers no)
		(fp_line
			(start -0.7874 -0.4064)
			(end -0.7874 0.4064)
			(stroke
				(width 0.1524)
				(type default)
			)
			(layer "B.SilkS")
		)
		(fp_line
			(start -0.7874 0.4064)
			(end 0.7874 0.4064)
			(stroke
				(width 0.1524)
				(type default)
			)
			(layer "B.SilkS")
		)
		(fp_line
			(start 0.7874 -0.4064)
			(end -0.7874 -0.4064)
			(stroke
				(width 0.1524)
				(type default)
			)
			(layer "B.SilkS")
		)
		(fp_line
			(start 0.7874 0.4064)
			(end 0.7874 -0.4064)
			(stroke
				(width 0.1524)
				(type default)
			)
			(layer "B.SilkS")
		)
		(fp_line
			(start -0.67945 -0.3048)
			(end -0.67945 0.3048)
			(stroke
				(width 0.1)
				(type default)
			)
			(layer "B.Fab")
		)
		(fp_line
			(start -0.67945 0.3048)
			(end -0.120396 0.3048)
			(stroke
				(width 0.1)
				(type default)
			)
			(layer "B.Fab")
		)
		(fp_line
			(start -0.12065 -0.3048)
			(end -0.67945 -0.3048)
			(stroke
				(width 0.1)
				(type default)
			)
			(layer "B.Fab")
		)
		(fp_line
			(start -0.12065 -0.2794)
			(end -0.12065 -0.3048)
			(stroke
				(width 0.1)
				(type default)
			)
			(layer "B.Fab")
		)
		(fp_line
			(start -0.120396 0.2794)
			(end 0.12065 0.2794)
			(stroke
				(width 0.1)
				(type default)
			)
			(layer "B.Fab")
		)
		(fp_line
			(start -0.120396 0.3048)
			(end -0.120396 0.2794)
			(stroke
				(width 0.1)
				(type default)
			)
			(layer "B.Fab")
		)
		(fp_line
			(start 0.12065 -0.305054)
			(end 0.12065 -0.2794)
			(stroke
				(width 0.1)
				(type default)
			)
			(layer "B.Fab")
		)
		(fp_line
			(start 0.12065 -0.2794)
			(end -0.12065 -0.2794)
			(stroke
				(width 0.1)
				(type default)
			)
			(layer "B.Fab")
		)
		(fp_line
			(start 0.12065 0.2794)
			(end 0.12065 0.3048)
			(stroke
				(width 0.1)
				(type default)
			)
			(layer "B.Fab")
		)
		(fp_line
			(start 0.12065 0.3048)
			(end 0.67945 0.3048)
			(stroke
				(width 0.1)
				(type default)
			)
			(layer "B.Fab")
		)
		(fp_line
			(start 0.67945 -0.305054)
			(end 0.12065 -0.305054)
			(stroke
				(width 0.1)
				(type default)
			)
			(layer "B.Fab")
		)
		(fp_line
			(start 0.67945 0.3048)
			(end 0.67945 -0.305054)
			(stroke
				(width 0.1)
				(type default)
			)
			(layer "B.Fab")
		)
		(pad "1" smd circle
			(at 0.40005 0 180)
			(size 0 0)
			(layers "B.Cu" "B.Mask" "B.Paste")
			(net "GND")
		)
		(pad "2" smd circle
			(at -0.40005 0 180)
			(size 0 0)
			(layers "B.Cu" "B.Mask" "B.Paste")
			(net "P3V3_AUX")
		)
	)
	(footprint ""
		(layer "B.Cu")
		(at 68.672202 -113.437924)
		(property "Reference" "R61"
			(at 0 0 0)
			(layer "B.SilkS")
			(hide yes)
			(effects
				(font
					(size 1.27 1.27)
				)
				(justify mirror)
			)
		)
		(property "Value" ""
			(at 0 0 0)
			(layer "B.Fab")
			(effects
				(font
					(size 1.27 1.27)
				)
				(justify mirror)
			)
		)
		(duplicate_pad_numbers_are_jumpers no)
		(fp_line
			(start -0.7874 -0.4064)
			(end -0.7874 0.4064)
			(stroke
				(width 0.1524)
				(type default)
			)
			(layer "B.SilkS")
		)
		(fp_line
			(start -0.7874 0.4064)
			(end 0.7874 0.4064)
			(stroke
				(width 0.1524)
				(type default)
			)
			(layer "B.SilkS")
		)
		(fp_line
			(start 0.7874 -0.4064)
			(end -0.7874 -0.4064)
			(stroke
				(width 0.1524)
				(type default)
			)
			(layer "B.SilkS")
		)
		(fp_line
			(start 0.7874 0.4064)
			(end 0.7874 -0.4064)
			(stroke
				(width 0.1524)
				(type default)
			)
			(layer "B.SilkS")
		)
		(fp_line
			(start -0.67945 -0.3048)
			(end -0.67945 0.3048)
			(stroke
				(width 0.1)
				(type default)
			)
			(layer "B.Fab")
		)
		(fp_line
			(start -0.67945 0.3048)
			(end -0.120396 0.3048)
			(stroke
				(width 0.1)
				(type default)
			)
			(layer "B.Fab")
		)
		(fp_line
			(start -0.12065 -0.3048)
			(end -0.67945 -0.3048)
			(stroke
				(width 0.1)
				(type default)
			)
			(layer "B.Fab")
		)
		(fp_line
			(start -0.12065 -0.2794)
			(end -0.12065 -0.3048)
			(stroke
				(width 0.1)
				(type default)
			)
			(layer "B.Fab")
		)
		(fp_line
			(start -0.120396 0.2794)
			(end 0.12065 0.2794)
			(stroke
				(width 0.1)
				(type default)
			)
			(layer "B.Fab")
		)
		(fp_line
			(start -0.120396 0.3048)
			(end -0.120396 0.2794)
			(stroke
				(width 0.1)
				(type default)
			)
			(layer "B.Fab")
		)
		(fp_line
			(start 0.12065 -0.305054)
			(end 0.12065 -0.2794)
			(stroke
				(width 0.1)
				(type default)
			)
			(layer "B.Fab")
		)
		(fp_line
			(start 0.12065 -0.2794)
			(end -0.12065 -0.2794)
			(stroke
				(width 0.1)
				(type default)
			)
			(layer "B.Fab")
		)
		(fp_line
			(start 0.12065 0.2794)
			(end 0.12065 0.3048)
			(stroke
				(width 0.1)
				(type default)
			)
			(layer "B.Fab")
		)
		(fp_line
			(start 0.12065 0.3048)
			(end 0.67945 0.3048)
			(stroke
				(width 0.1)
				(type default)
			)
			(layer "B.Fab")
		)
		(fp_line
			(start 0.67945 -0.305054)
			(end 0.12065 -0.305054)
			(stroke
				(width 0.1)
				(type default)
			)
			(layer "B.Fab")
		)
		(fp_line
			(start 0.67945 0.3048)
			(end 0.67945 -0.305054)
			(stroke
				(width 0.1)
				(type default)
			)
			(layer "B.Fab")
		)
		(pad "1" smd circle
			(at 0.40005 0 180)
			(size 0 0)
			(layers "B.Cu" "B.Mask" "B.Paste")
			(net "P3V3_NIC1")
		)
		(pad "2" smd circle
			(at -0.40005 0 180)
			(size 0 0)
			(layers "B.Cu" "B.Mask" "B.Paste")
			(net "SMB_NIC1_R_SDA")
		)
	)
	(footprint ""
		(layer "B.Cu")
		(at 224.269046 -143.094202 90)
		(property "Reference" "C2797"
			(at 0 0 90)
			(layer "B.SilkS")
			(hide yes)
			(effects
				(font
					(size 1.27 1.27)
				)
				(justify mirror)
			)
		)
		(property "Value" ""
			(at 0 0 90)
			(layer "B.Fab")
			(effects
				(font
					(size 1.27 1.27)
				)
				(justify mirror)
			)
		)
		(duplicate_pad_numbers_are_jumpers no)
		(fp_line
			(start 1.2954 -0.5842)
			(end -1.2954 -0.5842)
			(stroke
				(width 0.1524)
				(type default)
			)
			(layer "B.SilkS")
		)
		(fp_line
			(start -1.2954 -0.5842)
			(end -1.2954 0.5842)
			(stroke
				(width 0.1524)
				(type default)
			)
			(layer "B.SilkS")
		)
		(fp_line
			(start 1.2954 0.5842)
			(end 1.2954 -0.5842)
			(stroke
				(width 0.1524)
				(type default)
			)
			(layer "B.SilkS")
		)
		(fp_line
			(start -1.2954 0.5842)
			(end 1.2954 0.5842)
			(stroke
				(width 0.1524)
				(type default)
			)
			(layer "B.SilkS")
		)
		(fp_line
			(start 0.8636 -0.4572)
			(end -0.8636 -0.4572)
			(stroke
				(width 0.1)
				(type default)
			)
			(layer "B.Fab")
		)
		(fp_line
			(start -0.8636 -0.4572)
			(end -0.8636 -0.4064)
			(stroke
				(width 0.1)
				(type default)
			)
			(layer "B.Fab")
		)
		(fp_line
			(start 1.1938 -0.4064)
			(end 0.8636 -0.4064)
			(stroke
				(width 0.1)
				(type default)
			)
			(layer "B.Fab")
		)
		(fp_line
			(start 0.8636 -0.4064)
			(end 0.8636 -0.4572)
			(stroke
				(width 0.1)
				(type default)
			)
			(layer "B.Fab")
		)
		(fp_line
			(start -0.8636 -0.4064)
			(end -1.1938 -0.4064)
			(stroke
				(width 0.1)
				(type default)
			)
			(layer "B.Fab")
		)
		(fp_line
			(start -1.1938 -0.4064)
			(end -1.1938 0.4064)
			(stroke
				(width 0.1)
				(type default)
			)
			(layer "B.Fab")
		)
		(fp_line
			(start 1.1938 0.4064)
			(end 1.1938 -0.4064)
			(stroke
				(width 0.1)
				(type default)
			)
			(layer "B.Fab")
		)
		(fp_line
			(start 0.8636 0.4064)
			(end 1.1938 0.4064)
			(stroke
				(width 0.1)
				(type default)
			)
			(layer "B.Fab")
		)
		(fp_line
			(start -0.8636 0.4064)
			(end -0.8636 0.4572)
			(stroke
				(width 0.1)
				(type default)
			)
			(layer "B.Fab")
		)
		(fp_line
			(start -1.1938 0.4064)
			(end -0.8636 0.4064)
			(stroke
				(width 0.1)
				(type default)
			)
			(layer "B.Fab")
		)
		(fp_line
			(start 0.8636 0.4572)
			(end 0.8636 0.4064)
			(stroke
				(width 0.1)
				(type default)
			)
			(layer "B.Fab")
		)
		(fp_line
			(start -0.8636 0.4572)
			(end 0.8636 0.4572)
			(stroke
				(width 0.1)
				(type default)
			)
			(layer "B.Fab")
		)
		(pad "1" smd rect
			(at 0.7366 0)
			(size 0.7112 0.8128)
			(layers "B.Cu" "B.Mask" "B.Paste")
			(net "P3V3_CLK_GEN_VDDA25M_CK440_PEX")
		)
		(pad "2" smd rect
			(at -0.7366 0)
			(size 0.7112 0.8128)
			(layers "B.Cu" "B.Mask" "B.Paste")
			(net "GND")
		)
	)
	(footprint ""
		(layer "B.Cu")
		(at 278.064214 -144.421352 180)
		(property "Reference" "C910"
			(at 0 0 0)
			(layer "B.SilkS")
			(hide yes)
			(effects
				(font
					(size 1.27 1.27)
				)
				(justify mirror)
			)
		)
		(property "Value" ""
			(at 0 0 0)
			(layer "B.Fab")
			(effects
				(font
					(size 1.27 1.27)
				)
				(justify mirror)
			)
		)
		(duplicate_pad_numbers_are_jumpers no)
		(fp_line
			(start 0.299974 0.150114)
			(end 0.299974 -0.150114)
			(stroke
				(width 0.1)
				(type default)
			)
			(layer "B.Fab")
		)
		(fp_line
			(start 0.299974 -0.150114)
			(end -0.299974 -0.150114)
			(stroke
				(width 0.1)
				(type default)
			)
			(layer "B.Fab")
		)
		(fp_line
			(start -0.299974 0.150114)
			(end 0.299974 0.150114)
			(stroke
				(width 0.1)
				(type default)
			)
			(layer "B.Fab")
		)
		(fp_line
			(start -0.299974 -0.150114)
			(end -0.299974 0.150114)
			(stroke
				(width 0.1)
				(type default)
			)
			(layer "B.Fab")
		)
		(pad "1" smd rect
			(at 0.2667 0)
			(size 0.3048 0.381)
			(layers "B.Cu" "B.Mask" "B.Paste")
			(net "P12V_NIC4")
		)
		(pad "2" smd rect
			(at -0.2667 0)
			(size 0.3048 0.381)
			(layers "B.Cu" "B.Mask" "B.Paste")
			(net "GND")
		)
	)
)
